(kicad_pcb
	(version 20260206)
	(generator "pcbnew")
	(generator_version "10.0")
	(general
		(thickness 1.6)
		(legacy_teardrops no)
	)
	(paper "A4")
	(title_block
		(title "03242023_DA0F0TMBIJ0_F0T_Motherboard_J_brd_V01_OCP.brd")
		(comment 1 "Grand Teton / footprint 663 of 6105 (J21), pads 1-112 of 291")
	)
	(layers
		(0 "F.Cu" signal "TOP")
		(4 "In1.Cu" signal "GND")
		(6 "In2.Cu" signal "IN1")
		(8 "In3.Cu" signal "GND1")
		(10 "In4.Cu" signal "IN2")
		(12 "In5.Cu" signal "GND2")
		(14 "In6.Cu" signal "IN3")
		(16 "In7.Cu" signal "GND3")
		(18 "In8.Cu" signal "VCC")
		(20 "In9.Cu" signal "VCC1")
		(22 "In10.Cu" signal "GND4")
		(24 "In11.Cu" signal "IN4")
		(26 "In12.Cu" signal "GND5")
		(28 "In13.Cu" signal "IN5")
		(30 "In14.Cu" signal "GND6")
		(32 "In15.Cu" signal "IN6")
		(34 "In16.Cu" signal "GND7")
		(2 "B.Cu" signal "BOTTOM")
		(9 "F.Adhes" user "F.Adhesive")
		(11 "B.Adhes" user "B.Adhesive")
		(13 "F.Paste" user "Package Geometry/Pastemask Top")
		(15 "B.Paste" user "Package Geometry/Pastemask Bottom")
		(5 "F.SilkS" user "Ref Des/Silkscreen Top")
		(7 "B.SilkS" user "Ref Des/Silkscreen Bottom")
		(1 "F.Mask" user "Board Geometry/Soldermask Top")
		(3 "B.Mask" user "Board Geometry/Soldermask Bottom")
		(17 "Dwgs.User" user "User.Drawings")
		(19 "Cmts.User" user "User.Comments")
		(21 "Eco1.User" user "User.Eco1")
		(23 "Eco2.User" user "User.Eco2")
		(25 "Edge.Cuts" user "Board Geometry/Outline")
		(27 "Margin" user)
		(31 "F.CrtYd" user "Package Geometry/Place Bound Top")
		(29 "B.CrtYd" user "Package Geometry/Place Bound Bottom")
		(35 "F.Fab" user "Ref Des/Assembly Top")
		(33 "B.Fab" user "Ref Des/Assembly Bottom")
	)
	(footprint ""
		(layer "F.Cu")
		(at 25.27808 -258.091686)
		(property "Reference" "J21"
			(at -0.325882 -81.821274 0)
			(unlocked yes)
			(layer "F.SilkS")
			(effects
				(font
					(size 0.7874 0.5842)
					(thickness 0.1524)
				)
				(justify left)
			)
		)
		(property "Value" ""
			(at 0 0 0)
			(layer "F.Fab")
			(effects
				(font
					(size 1.27 1.27)
				)
			)
		)
		(duplicate_pad_numbers_are_jumpers no)
		(pad "1" smd rect
			(at -2.050034 -63.324994 270)
			(size 0.519938 1.4986)
			(layers "F.Cu" "F.Mask" "F.Paste")
			(net "P12V_S3_AUX_CPU1_NVDIMM")
		)
		(pad "2" smd rect
			(at -2.050034 -62.47511 270)
			(size 0.519938 1.4986)
			(layers "F.Cu" "F.Mask" "F.Paste")
			(net "TP_CHC_CPU1_DIMM1_FRU_0")
		)
		(pad "3" smd rect
			(at -2.050034 -61.624972 270)
			(size 0.519938 1.4986)
			(layers "F.Cu" "F.Mask" "F.Paste")
			(net "P3V3_AUX")
		)
		(pad "4" smd rect
			(at -2.050034 -60.775088 270)
			(size 0.519938 1.4986)
			(layers "F.Cu" "F.Mask" "F.Paste")
			(net "I3C_SPD_DDRABCD_CPU1_LVC1_SCL_4")
		)
		(pad "5" smd rect
			(at -2.050034 -59.92495 270)
			(size 0.519938 1.4986)
			(layers "F.Cu" "F.Mask" "F.Paste")
			(net "I3C_SPD_DDRABCD_CPU1_LVC1_SDA")
		)
		(pad "6" smd rect
			(at -2.050034 -59.075066 270)
			(size 0.519938 1.4986)
			(layers "F.Cu" "F.Mask" "F.Paste")
			(net "GND")
		)
		(pad "7" smd rect
			(at -2.050034 -58.224928 270)
			(size 0.519938 1.4986)
			(layers "F.Cu" "F.Mask" "F.Paste")
			(net "M_C_CPU1_SA_DQ<0>")
		)
		(pad "8" smd rect
			(at -2.050034 -57.375044 270)
			(size 0.519938 1.4986)
			(layers "F.Cu" "F.Mask" "F.Paste")
			(net "GND")
		)
		(pad "9" smd rect
			(at -2.050034 -56.524906 270)
			(size 0.519938 1.4986)
			(layers "F.Cu" "F.Mask" "F.Paste")
			(net "M_C_CPU1_SA_DQ<1>")
		)
		(pad "10" smd rect
			(at -2.050034 -55.675022 270)
			(size 0.519938 1.4986)
			(layers "F.Cu" "F.Mask" "F.Paste")
			(net "GND")
		)
		(pad "11" smd rect
			(at -2.050034 -54.824884 270)
			(size 0.519938 1.4986)
			(layers "F.Cu" "F.Mask" "F.Paste")
			(net "M_C_CPU1_SA_DQS_DP<0>")
		)
		(pad "12" smd rect
			(at -2.050034 -53.975 270)
			(size 0.519938 1.4986)
			(layers "F.Cu" "F.Mask" "F.Paste")
			(net "M_C_CPU1_SA_DQS_DN<0>")
		)
		(pad "13" smd rect
			(at -2.050034 -53.125116 270)
			(size 0.519938 1.4986)
			(layers "F.Cu" "F.Mask" "F.Paste")
			(net "GND")
		)
		(pad "14" smd rect
			(at -2.050034 -52.274978 270)
			(size 0.519938 1.4986)
			(layers "F.Cu" "F.Mask" "F.Paste")
			(net "M_C_CPU1_SA_DQ<4>")
		)
		(pad "15" smd rect
			(at -2.050034 -51.425094 270)
			(size 0.519938 1.4986)
			(layers "F.Cu" "F.Mask" "F.Paste")
			(net "GND")
		)
		(pad "16" smd rect
			(at -2.050034 -50.574956 270)
			(size 0.519938 1.4986)
			(layers "F.Cu" "F.Mask" "F.Paste")
			(net "M_C_CPU1_SA_DQ<5>")
		)
		(pad "17" smd rect
			(at -2.050034 -49.725072 270)
			(size 0.519938 1.4986)
			(layers "F.Cu" "F.Mask" "F.Paste")
			(net "GND")
		)
		(pad "18" smd rect
			(at -2.050034 -48.874934 270)
			(size 0.519938 1.4986)
			(layers "F.Cu" "F.Mask" "F.Paste")
			(net "M_C_CPU1_SA_DQ<8>")
		)
		(pad "19" smd rect
			(at -2.050034 -48.02505 270)
			(size 0.519938 1.4986)
			(layers "F.Cu" "F.Mask" "F.Paste")
			(net "GND")
		)
		(pad "20" smd rect
			(at -2.050034 -47.174912 270)
			(size 0.519938 1.4986)
			(layers "F.Cu" "F.Mask" "F.Paste")
			(net "M_C_CPU1_SA_DQ<9>")
		)
		(pad "21" smd rect
			(at -2.050034 -46.325028 270)
			(size 0.519938 1.4986)
			(layers "F.Cu" "F.Mask" "F.Paste")
			(net "GND")
		)
		(pad "22" smd rect
			(at -2.050034 -45.47489 270)
			(size 0.519938 1.4986)
			(layers "F.Cu" "F.Mask" "F.Paste")
			(net "M_C_CPU1_SA_DQS_DP<1>")
		)
		(pad "23" smd rect
			(at -2.050034 -44.625006 270)
			(size 0.519938 1.4986)
			(layers "F.Cu" "F.Mask" "F.Paste")
			(net "M_C_CPU1_SA_DQS_DN<1>")
		)
		(pad "24" smd rect
			(at -2.050034 -43.775122 270)
			(size 0.519938 1.4986)
			(layers "F.Cu" "F.Mask" "F.Paste")
			(net "GND")
		)
		(pad "25" smd rect
			(at -2.050034 -42.924984 270)
			(size 0.519938 1.4986)
			(layers "F.Cu" "F.Mask" "F.Paste")
			(net "M_C_CPU1_SA_DQ<12>")
		)
		(pad "26" smd rect
			(at -2.050034 -42.0751 270)
			(size 0.519938 1.4986)
			(layers "F.Cu" "F.Mask" "F.Paste")
			(net "GND")
		)
		(pad "27" smd rect
			(at -2.050034 -41.224962 270)
			(size 0.519938 1.4986)
			(layers "F.Cu" "F.Mask" "F.Paste")
			(net "M_C_CPU1_SA_DQ<13>")
		)
		(pad "28" smd rect
			(at -2.050034 -40.375078 270)
			(size 0.519938 1.4986)
			(layers "F.Cu" "F.Mask" "F.Paste")
			(net "GND")
		)
		(pad "29" smd rect
			(at -2.050034 -39.52494 270)
			(size 0.519938 1.4986)
			(layers "F.Cu" "F.Mask" "F.Paste")
			(net "M_C_CPU1_SA_DQ<16>")
		)
		(pad "30" smd rect
			(at -2.050034 -38.675056 270)
			(size 0.519938 1.4986)
			(layers "F.Cu" "F.Mask" "F.Paste")
			(net "GND")
		)
		(pad "31" smd rect
			(at -2.050034 -37.824918 270)
			(size 0.519938 1.4986)
			(layers "F.Cu" "F.Mask" "F.Paste")
			(net "M_C_CPU1_SA_DQ<17>")
		)
		(pad "32" smd rect
			(at -2.050034 -36.975034 270)
			(size 0.519938 1.4986)
			(layers "F.Cu" "F.Mask" "F.Paste")
			(net "GND")
		)
		(pad "33" smd rect
			(at -2.050034 -36.124896 270)
			(size 0.519938 1.4986)
			(layers "F.Cu" "F.Mask" "F.Paste")
			(net "M_C_CPU1_SA_DQS_DP<2>")
		)
		(pad "34" smd rect
			(at -2.050034 -35.275012 270)
			(size 0.519938 1.4986)
			(layers "F.Cu" "F.Mask" "F.Paste")
			(net "M_C_CPU1_SA_DQS_DN<2>")
		)
		(pad "35" smd rect
			(at -2.050034 -34.425128 270)
			(size 0.519938 1.4986)
			(layers "F.Cu" "F.Mask" "F.Paste")
			(net "GND")
		)
		(pad "36" smd rect
			(at -2.050034 -33.57499 270)
			(size 0.519938 1.4986)
			(layers "F.Cu" "F.Mask" "F.Paste")
			(net "M_C_CPU1_SA_DQ<20>")
		)
		(pad "37" smd rect
			(at -2.050034 -32.725106 270)
			(size 0.519938 1.4986)
			(layers "F.Cu" "F.Mask" "F.Paste")
			(net "GND")
		)
		(pad "38" smd rect
			(at -2.050034 -31.874968 270)
			(size 0.519938 1.4986)
			(layers "F.Cu" "F.Mask" "F.Paste")
			(net "M_C_CPU1_SA_DQ<21>")
		)
		(pad "39" smd rect
			(at -2.050034 -31.025084 270)
			(size 0.519938 1.4986)
			(layers "F.Cu" "F.Mask" "F.Paste")
			(net "GND")
		)
		(pad "40" smd rect
			(at -2.050034 -30.174946 270)
			(size 0.519938 1.4986)
			(layers "F.Cu" "F.Mask" "F.Paste")
			(net "M_C_CPU1_SA_DQ<24>")
		)
		(pad "41" smd rect
			(at -2.050034 -29.325062 270)
			(size 0.519938 1.4986)
			(layers "F.Cu" "F.Mask" "F.Paste")
			(net "GND")
		)
		(pad "42" smd rect
			(at -2.050034 -28.474924 270)
			(size 0.519938 1.4986)
			(layers "F.Cu" "F.Mask" "F.Paste")
			(net "M_C_CPU1_SA_DQ<25>")
		)
		(pad "43" smd rect
			(at -2.050034 -27.62504 270)
			(size 0.519938 1.4986)
			(layers "F.Cu" "F.Mask" "F.Paste")
			(net "GND")
		)
		(pad "44" smd rect
			(at -2.050034 -26.774902 270)
			(size 0.519938 1.4986)
			(layers "F.Cu" "F.Mask" "F.Paste")
			(net "M_C_CPU1_SA_DQS_DP<3>")
		)
		(pad "45" smd rect
			(at -2.050034 -25.925018 270)
			(size 0.519938 1.4986)
			(layers "F.Cu" "F.Mask" "F.Paste")
			(net "M_C_CPU1_SA_DQS_DN<3>")
		)
		(pad "46" smd rect
			(at -2.050034 -25.07488 270)
			(size 0.519938 1.4986)
			(layers "F.Cu" "F.Mask" "F.Paste")
			(net "GND")
		)
		(pad "47" smd rect
			(at -2.050034 -24.224996 270)
			(size 0.519938 1.4986)
			(layers "F.Cu" "F.Mask" "F.Paste")
			(net "M_C_CPU1_SA_DQ<28>")
		)
		(pad "48" smd rect
			(at -2.050034 -23.375112 270)
			(size 0.519938 1.4986)
			(layers "F.Cu" "F.Mask" "F.Paste")
			(net "GND")
		)
		(pad "49" smd rect
			(at -2.050034 -22.524974 270)
			(size 0.519938 1.4986)
			(layers "F.Cu" "F.Mask" "F.Paste")
			(net "M_C_CPU1_SA_DQ<29>")
		)
		(pad "50" smd rect
			(at -2.050034 -21.67509 270)
			(size 0.519938 1.4986)
			(layers "F.Cu" "F.Mask" "F.Paste")
			(net "GND")
		)
		(pad "51" smd rect
			(at -2.050034 -20.824952 270)
			(size 0.519938 1.4986)
			(layers "F.Cu" "F.Mask" "F.Paste")
			(net "M_C_CPU1_SA_CB<0>")
		)
		(pad "52" smd rect
			(at -2.050034 -19.975068 270)
			(size 0.519938 1.4986)
			(layers "F.Cu" "F.Mask" "F.Paste")
			(net "GND")
		)
		(pad "53" smd rect
			(at -2.050034 -19.12493 270)
			(size 0.519938 1.4986)
			(layers "F.Cu" "F.Mask" "F.Paste")
			(net "M_C_CPU1_SA_CB<1>")
		)
		(pad "54" smd rect
			(at -2.050034 -18.275046 270)
			(size 0.519938 1.4986)
			(layers "F.Cu" "F.Mask" "F.Paste")
			(net "GND")
		)
		(pad "55" smd rect
			(at -2.050034 -17.424908 270)
			(size 0.519938 1.4986)
			(layers "F.Cu" "F.Mask" "F.Paste")
			(net "M_C_CPU1_SA_DQS_DP<4>")
		)
		(pad "56" smd rect
			(at -2.050034 -16.575024 270)
			(size 0.519938 1.4986)
			(layers "F.Cu" "F.Mask" "F.Paste")
			(net "M_C_CPU1_SA_DQS_DN<4>")
		)
		(pad "57" smd rect
			(at -2.050034 -15.724886 270)
			(size 0.519938 1.4986)
			(layers "F.Cu" "F.Mask" "F.Paste")
			(net "GND")
		)
		(pad "58" smd rect
			(at -2.050034 -14.875002 270)
			(size 0.519938 1.4986)
			(layers "F.Cu" "F.Mask" "F.Paste")
			(net "M_C_CPU1_SA_CB<4>")
		)
		(pad "59" smd rect
			(at -2.050034 -14.025118 270)
			(size 0.519938 1.4986)
			(layers "F.Cu" "F.Mask" "F.Paste")
			(net "GND")
		)
		(pad "60" smd rect
			(at -2.050034 -13.17498 270)
			(size 0.519938 1.4986)
			(layers "F.Cu" "F.Mask" "F.Paste")
			(net "M_C_CPU1_SA_CB<5>")
		)
		(pad "61" smd rect
			(at -2.050034 -12.325096 270)
			(size 0.519938 1.4986)
			(layers "F.Cu" "F.Mask" "F.Paste")
			(net "GND")
		)
		(pad "62" smd rect
			(at -2.050034 -11.474958 270)
			(size 0.519938 1.4986)
			(layers "F.Cu" "F.Mask" "F.Paste")
			(net "M_C_CPU1_ALERT_N")
		)
		(pad "63" smd rect
			(at -2.050034 -10.625074 270)
			(size 0.519938 1.4986)
			(layers "F.Cu" "F.Mask" "F.Paste")
			(net "GND")
		)
		(pad "64" smd rect
			(at -2.050034 -9.774936 270)
			(size 0.519938 1.4986)
			(layers "F.Cu" "F.Mask" "F.Paste")
			(net "M_C_CPU1_SA_CS_N<0>")
		)
		(pad "65" smd rect
			(at -2.050034 -8.925052 270)
			(size 0.519938 1.4986)
			(layers "F.Cu" "F.Mask" "F.Paste")
			(net "GND")
		)
		(pad "66" smd rect
			(at -2.050034 -8.074914 270)
			(size 0.519938 1.4986)
			(layers "F.Cu" "F.Mask" "F.Paste")
			(net "M_C_CPU1_SA_CA<0>")
		)
		(pad "67" smd rect
			(at -2.050034 -7.22503 270)
			(size 0.519938 1.4986)
			(layers "F.Cu" "F.Mask" "F.Paste")
			(net "GND")
		)
		(pad "68" smd rect
			(at -2.050034 -6.374892 270)
			(size 0.519938 1.4986)
			(layers "F.Cu" "F.Mask" "F.Paste")
			(net "M_C_CPU1_SA_CA<2>")
		)
		(pad "69" smd rect
			(at -2.050034 -5.525008 270)
			(size 0.519938 1.4986)
			(layers "F.Cu" "F.Mask" "F.Paste")
			(net "GND")
		)
		(pad "70" smd rect
			(at -2.050034 -4.675124 270)
			(size 0.519938 1.4986)
			(layers "F.Cu" "F.Mask" "F.Paste")
			(net "M_C_CPU1_SA_CA<4>")
		)
		(pad "71" smd rect
			(at -2.050034 -3.824986 270)
			(size 0.519938 1.4986)
			(layers "F.Cu" "F.Mask" "F.Paste")
			(net "GND")
		)
		(pad "72" smd rect
			(at -2.050034 -2.975102 270)
			(size 0.519938 1.4986)
			(layers "F.Cu" "F.Mask" "F.Paste")
			(net "M_C_CPU1_SA_CA<6>")
		)
		(pad "73" smd rect
			(at -2.050034 -2.124964 270)
			(size 0.519938 1.4986)
			(layers "F.Cu" "F.Mask" "F.Paste")
			(net "GND")
		)
		(pad "74" smd rect
			(at -2.050034 -1.27508 270)
			(size 0.519938 1.4986)
			(layers "F.Cu" "F.Mask" "F.Paste")
			(net "M_C_CPU1_SA_PAR")
		)
		(pad "75" smd rect
			(at -2.050034 -0.424942 270)
			(size 0.519938 1.4986)
			(layers "F.Cu" "F.Mask" "F.Paste")
			(net "GND")
		)
		(pad "76" smd rect
			(at -2.050034 5.525008 270)
			(size 0.519938 1.4986)
			(layers "F.Cu" "F.Mask" "F.Paste")
			(net "M_C_CPU1_SB_CA<0>")
		)
		(pad "77" smd rect
			(at -2.050034 6.374892 270)
			(size 0.519938 1.4986)
			(layers "F.Cu" "F.Mask" "F.Paste")
			(net "GND")
		)
		(pad "78" smd rect
			(at -2.050034 7.22503 270)
			(size 0.519938 1.4986)
			(layers "F.Cu" "F.Mask" "F.Paste")
			(net "M_C_CPU1_SB_CA<2>")
		)
		(pad "79" smd rect
			(at -2.050034 8.074914 270)
			(size 0.519938 1.4986)
			(layers "F.Cu" "F.Mask" "F.Paste")
			(net "GND")
		)
		(pad "80" smd rect
			(at -2.050034 8.925052 270)
			(size 0.519938 1.4986)
			(layers "F.Cu" "F.Mask" "F.Paste")
			(net "M_C_CPU1_SB_CA<4>")
		)
		(pad "81" smd rect
			(at -2.050034 9.774936 270)
			(size 0.519938 1.4986)
			(layers "F.Cu" "F.Mask" "F.Paste")
			(net "GND")
		)
		(pad "82" smd rect
			(at -2.050034 10.625074 270)
			(size 0.519938 1.4986)
			(layers "F.Cu" "F.Mask" "F.Paste")
			(net "M_C_CPU1_SB_CA<6>")
		)
		(pad "83" smd rect
			(at -2.050034 11.474958 270)
			(size 0.519938 1.4986)
			(layers "F.Cu" "F.Mask" "F.Paste")
			(net "GND")
		)
		(pad "84" smd rect
			(at -2.050034 12.325096 270)
			(size 0.519938 1.4986)
			(layers "F.Cu" "F.Mask" "F.Paste")
			(net "M_C_CPU1_SB_CS_N<0>")
		)
		(pad "85" smd rect
			(at -2.050034 13.17498 270)
			(size 0.519938 1.4986)
			(layers "F.Cu" "F.Mask" "F.Paste")
			(net "GND")
		)
		(pad "86" smd rect
			(at -2.050034 14.025118 270)
			(size 0.519938 1.4986)
			(layers "F.Cu" "F.Mask" "F.Paste")
			(net "M_C_CPU1_SA_RSP<0>")
		)
		(pad "87" smd rect
			(at -2.050034 14.875002 270)
			(size 0.519938 1.4986)
			(layers "F.Cu" "F.Mask" "F.Paste")
			(net "M_C_CPU1_SB_RSP<0>")
		)
		(pad "88" smd rect
			(at -2.050034 15.724886 270)
			(size 0.519938 1.4986)
			(layers "F.Cu" "F.Mask" "F.Paste")
			(net "GND")
		)
		(pad "89" smd rect
			(at -2.050034 16.575024 270)
			(size 0.519938 1.4986)
			(layers "F.Cu" "F.Mask" "F.Paste")
			(net "M_C_CPU1_SB_CB<4>")
		)
		(pad "90" smd rect
			(at -2.050034 17.424908 270)
			(size 0.519938 1.4986)
			(layers "F.Cu" "F.Mask" "F.Paste")
			(net "GND")
		)
		(pad "91" smd rect
			(at -2.050034 18.275046 270)
			(size 0.519938 1.4986)
			(layers "F.Cu" "F.Mask" "F.Paste")
			(net "M_C_CPU1_SB_CB<5>")
		)
		(pad "92" smd rect
			(at -2.050034 19.12493 270)
			(size 0.519938 1.4986)
			(layers "F.Cu" "F.Mask" "F.Paste")
			(net "GND")
		)
		(pad "93" smd rect
			(at -2.050034 19.975068 270)
			(size 0.519938 1.4986)
			(layers "F.Cu" "F.Mask" "F.Paste")
			(net "M_C_CPU1_SB_DQS_DP<9>")
		)
		(pad "94" smd rect
			(at -2.050034 20.824952 270)
			(size 0.519938 1.4986)
			(layers "F.Cu" "F.Mask" "F.Paste")
			(net "M_C_CPU1_SB_DQS_DN<9>")
		)
		(pad "95" smd rect
			(at -2.050034 21.67509 270)
			(size 0.519938 1.4986)
			(layers "F.Cu" "F.Mask" "F.Paste")
			(net "GND")
		)
		(pad "96" smd rect
			(at -2.050034 22.524974 270)
			(size 0.519938 1.4986)
			(layers "F.Cu" "F.Mask" "F.Paste")
			(net "M_C_CPU1_SB_CB<0>")
		)
		(pad "97" smd rect
			(at -2.050034 23.375112 270)
			(size 0.519938 1.4986)
			(layers "F.Cu" "F.Mask" "F.Paste")
			(net "GND")
		)
		(pad "98" smd rect
			(at -2.050034 24.224996 270)
			(size 0.519938 1.4986)
			(layers "F.Cu" "F.Mask" "F.Paste")
			(net "M_C_CPU1_SB_CB<1>")
		)
		(pad "99" smd rect
			(at -2.050034 25.07488 270)
			(size 0.519938 1.4986)
			(layers "F.Cu" "F.Mask" "F.Paste")
			(net "GND")
		)
		(pad "100" smd rect
			(at -2.050034 25.925018 270)
			(size 0.519938 1.4986)
			(layers "F.Cu" "F.Mask" "F.Paste")
			(net "M_C_CPU1_SB_DQ<0>")
		)
		(pad "101" smd rect
			(at -2.050034 26.774902 270)
			(size 0.519938 1.4986)
			(layers "F.Cu" "F.Mask" "F.Paste")
			(net "GND")
		)
		(pad "102" smd rect
			(at -2.050034 27.62504 270)
			(size 0.519938 1.4986)
			(layers "F.Cu" "F.Mask" "F.Paste")
			(net "M_C_CPU1_SB_DQ<1>")
		)
		(pad "103" smd rect
			(at -2.050034 28.474924 270)
			(size 0.519938 1.4986)
			(layers "F.Cu" "F.Mask" "F.Paste")
			(net "GND")
		)
		(pad "104" smd rect
			(at -2.050034 29.325062 270)
			(size 0.519938 1.4986)
			(layers "F.Cu" "F.Mask" "F.Paste")
			(net "M_C_CPU1_SB_DQS_DP<0>")
		)
		(pad "105" smd rect
			(at -2.050034 30.174946 270)
			(size 0.519938 1.4986)
			(layers "F.Cu" "F.Mask" "F.Paste")
			(net "M_C_CPU1_SB_DQS_DN<0>")
		)
		(pad "106" smd rect
			(at -2.050034 31.025084 270)
			(size 0.519938 1.4986)
			(layers "F.Cu" "F.Mask" "F.Paste")
			(net "GND")
		)
		(pad "107" smd rect
			(at -2.050034 31.874968 270)
			(size 0.519938 1.4986)
			(layers "F.Cu" "F.Mask" "F.Paste")
			(net "M_C_CPU1_SB_DQ<4>")
		)
		(pad "108" smd rect
			(at -2.050034 32.725106 270)
			(size 0.519938 1.4986)
			(layers "F.Cu" "F.Mask" "F.Paste")
			(net "GND")
		)
		(pad "109" smd rect
			(at -2.050034 33.57499 270)
			(size 0.519938 1.4986)
			(layers "F.Cu" "F.Mask" "F.Paste")
			(net "M_C_CPU1_SB_DQ<5>")
		)
		(pad "110" smd rect
			(at -2.050034 34.425128 270)
			(size 0.519938 1.4986)
			(layers "F.Cu" "F.Mask" "F.Paste")
			(net "GND")
		)
		(pad "111" smd rect
			(at -2.050034 35.275012 270)
			(size 0.519938 1.4986)
			(layers "F.Cu" "F.Mask" "F.Paste")
			(net "M_C_CPU1_SB_DQ<8>")
		)
		(pad "112" smd rect
			(at -2.050034 36.124896 270)
			(size 0.519938 1.4986)
			(layers "F.Cu" "F.Mask" "F.Paste")
			(net "GND")
		)
	)
)
